# T6G (Grand Teton) — schematic netlist excerpt (pin names and nets, part order shuffled) for the footprints in the layout excerpt that follows; sources: Cadence DE-HDL packaged netlist, KiCad conversion of 04192023_DAF0TMB3IC0_F0TG_MB_C_brd_V02_OCP.brd

C2170  Q_CAP  22UF 4V 20% X6S  pkg C0402  page 69 : A = PVDDCR_CPU0_P0 ; B = GND
C968  Q_CAP  0.1UF 10V 10% X7S  pkg C0201  page 301 : A = P0V9_CPU0_RT2_2A ; B = GND
R3092  Q_RES  130 1% CHIP  pkg 0402LF  page 255 : A = LED_PWRGD_PVDDIO_P0_R ; B = P3V3_AUX

(kicad_pcb
	(version 20260206)
	(generator "pcbnew")
	(generator_version "10.0")
	(general
		(thickness 1.6)
		(legacy_teardrops no)
	)
	(paper "A4")
	(title_block
		(title "04192023_DAF0TMB3IC0_F0TG_MB_C_brd_V02_OCP.brd")
		(comment 1 "Grand Teton / footprints 6841-6843 of 8354")
	)
	(layers
		(0 "F.Cu" signal "TOP")
		(4 "In1.Cu" signal "GND")
		(6 "In2.Cu" signal "IN1")
		(8 "In3.Cu" signal "GND1")
		(10 "In4.Cu" signal "IN2")
		(12 "In5.Cu" signal "GND2")
		(14 "In6.Cu" signal "IN3")
		(16 "In7.Cu" signal "GND3")
		(18 "In8.Cu" signal "VCC")
		(20 "In9.Cu" signal "VCC1")
		(22 "In10.Cu" signal "GND4")
		(24 "In11.Cu" signal "IN4")
		(26 "In12.Cu" signal "GND5")
		(28 "In13.Cu" signal "IN5")
		(30 "In14.Cu" signal "GND6")
		(32 "In15.Cu" signal "IN6")
		(34 "In16.Cu" signal "GND7")
		(2 "B.Cu" signal "BOTTOM")
		(9 "F.Adhes" user "F.Adhesive")
		(11 "B.Adhes" user "B.Adhesive")
		(13 "F.Paste" user "Package Geometry/Pastemask Top")
		(15 "B.Paste" user "Package Geometry/Pastemask Bottom")
		(5 "F.SilkS" user "Ref Des/Silkscreen Top")
		(7 "B.SilkS" user "Ref Des/Silkscreen Bottom")
		(1 "F.Mask" user "Board Geometry/Soldermask Top")
		(3 "B.Mask" user "Board Geometry/Soldermask Bottom")
		(17 "Dwgs.User" user "User.Drawings")
		(19 "Cmts.User" user "User.Comments")
		(21 "Eco1.User" user "User.Eco1")
		(23 "Eco2.User" user "User.Eco2")
		(25 "Edge.Cuts" user "Board Geometry/Outline")
		(27 "Margin" user)
		(31 "F.CrtYd" user "Package Geometry/Place Bound Top")
		(29 "B.CrtYd" user "Package Geometry/Place Bound Bottom")
		(35 "F.Fab" user "Ref Des/Assembly Top")
		(33 "B.Fab" user "Ref Des/Assembly Bottom")
	)
	(footprint ""
		(layer "B.Cu")
		(at 330.731876 -66.708782 90)
		(property "Reference" "R3092"
			(at 0 0 90)
			(layer "B.SilkS")
			(hide yes)
			(effects
				(font
					(size 1.27 1.27)
				)
				(justify mirror)
			)
		)
		(property "Value" ""
			(at 0 0 90)
			(layer "B.Fab")
			(effects
				(font
					(size 1.27 1.27)
				)
				(justify mirror)
			)
		)
		(duplicate_pad_numbers_are_jumpers no)
		(fp_line
			(start 0.7874 -0.4064)
			(end -0.7874 -0.4064)
			(stroke
				(width 0.1524)
				(type default)
			)
			(layer "B.SilkS")
		)
		(fp_line
			(start -0.7874 -0.4064)
			(end -0.7874 0.4064)
			(stroke
				(width 0.1524)
				(type default)
			)
			(layer "B.SilkS")
		)
		(fp_line
			(start 0.7874 0.4064)
			(end 0.7874 -0.4064)
			(stroke
				(width 0.1524)
				(type default)
			)
			(layer "B.SilkS")
		)
		(fp_line
			(start -0.7874 0.4064)
			(end 0.7874 0.4064)
			(stroke
				(width 0.1524)
				(type default)
			)
			(layer "B.SilkS")
		)
		(fp_line
			(start 0.67945 -0.305054)
			(end 0.12065 -0.305054)
			(stroke
				(width 0.1)
				(type default)
			)
			(layer "B.Fab")
		)
		(fp_line
			(start 0.12065 -0.305054)
			(end 0.12065 -0.2794)
			(stroke
				(width 0.1)
				(type default)
			)
			(layer "B.Fab")
		)
		(fp_line
			(start -0.12065 -0.3048)
			(end -0.67945 -0.3048)
			(stroke
				(width 0.1)
				(type default)
			)
			(layer "B.Fab")
		)
		(fp_line
			(start -0.67945 -0.3048)
			(end -0.67945 0.3048)
			(stroke
				(width 0.1)
				(type default)
			)
			(layer "B.Fab")
		)
		(fp_line
			(start 0.12065 -0.2794)
			(end -0.12065 -0.2794)
			(stroke
				(width 0.1)
				(type default)
			)
			(layer "B.Fab")
		)
		(fp_line
			(start -0.12065 -0.2794)
			(end -0.12065 -0.3048)
			(stroke
				(width 0.1)
				(type default)
			)
			(layer "B.Fab")
		)
		(fp_line
			(start 0.12065 0.2794)
			(end 0.12065 0.3048)
			(stroke
				(width 0.1)
				(type default)
			)
			(layer "B.Fab")
		)
		(fp_line
			(start -0.120396 0.2794)
			(end 0.12065 0.2794)
			(stroke
				(width 0.1)
				(type default)
			)
			(layer "B.Fab")
		)
		(fp_line
			(start 0.67945 0.3048)
			(end 0.67945 -0.305054)
			(stroke
				(width 0.1)
				(type default)
			)
			(layer "B.Fab")
		)
		(fp_line
			(start 0.12065 0.3048)
			(end 0.67945 0.3048)
			(stroke
				(width 0.1)
				(type default)
			)
			(layer "B.Fab")
		)
		(fp_line
			(start -0.120396 0.3048)
			(end -0.120396 0.2794)
			(stroke
				(width 0.1)
				(type default)
			)
			(layer "B.Fab")
		)
		(fp_line
			(start -0.67945 0.3048)
			(end -0.120396 0.3048)
			(stroke
				(width 0.1)
				(type default)
			)
			(layer "B.Fab")
		)
		(pad "1" smd circle
			(at 0.40005 0 270)
			(size 0 0)
			(layers "B.Cu" "B.Mask" "B.Paste")
			(net "LED_PWRGD_PVDDIO_P0_R")
		)
		(pad "2" smd circle
			(at -0.40005 0 270)
			(size 0 0)
			(layers "B.Cu" "B.Mask" "B.Paste")
			(net "P3V3_AUX")
		)
	)
	(footprint ""
		(layer "B.Cu")
		(at 403.14626 -396.393162 -90)
		(property "Reference" "C968"
			(at 0 0 90)
			(layer "B.SilkS")
			(hide yes)
			(effects
				(font
					(size 1.27 1.27)
				)
				(justify mirror)
			)
		)
		(property "Value" ""
			(at 0 0 90)
			(layer "B.Fab")
			(effects
				(font
					(size 1.27 1.27)
				)
				(justify mirror)
			)
		)
		(duplicate_pad_numbers_are_jumpers no)
		(fp_line
			(start -0.299974 0.150114)
			(end 0.299974 0.150114)
			(stroke
				(width 0.1)
				(type default)
			)
			(layer "B.Fab")
		)
		(fp_line
			(start 0.299974 0.150114)
			(end 0.299974 -0.150114)
			(stroke
				(width 0.1)
				(type default)
			)
			(layer "B.Fab")
		)
		(fp_line
			(start -0.299974 -0.150114)
			(end -0.299974 0.150114)
			(stroke
				(width 0.1)
				(type default)
			)
			(layer "B.Fab")
		)
		(fp_line
			(start 0.299974 -0.150114)
			(end -0.299974 -0.150114)
			(stroke
				(width 0.1)
				(type default)
			)
			(layer "B.Fab")
		)
		(pad "1" smd rect
			(at 0.2667 0 90)
			(size 0.3048 0.381)
			(layers "B.Cu" "B.Mask" "B.Paste")
			(net "P0V9_CPU0_RT2_2A")
		)
		(pad "2" smd rect
			(at -0.2667 0 90)
			(size 0.3048 0.381)
			(layers "B.Cu" "B.Mask" "B.Paste")
			(net "GND")
		)
	)
	(footprint ""
		(layer "B.Cu")
		(at 354.425758 -250.89231 180)
		(property "Reference" "C2170"
			(at 0 0 0)
			(layer "B.SilkS")
			(hide yes)
			(effects
				(font
					(size 1.27 1.27)
				)
				(justify mirror)
			)
		)
		(property "Value" ""
			(at 0 0 0)
			(layer "B.Fab")
			(effects
				(font
					(size 1.27 1.27)
				)
				(justify mirror)
			)
		)
		(duplicate_pad_numbers_are_jumpers no)
		(fp_line
			(start 0.7874 0.4064)
			(end 0.7874 -0.4064)
			(stroke
				(width 0.1524)
				(type default)
			)
			(layer "B.SilkS")
		)
		(fp_line
			(start 0.7874 -0.4064)
			(end -0.7874 -0.4064)
			(stroke
				(width 0.1524)
				(type default)
			)
			(layer "B.SilkS")
		)
		(fp_line
			(start -0.7874 0.4064)
			(end 0.7874 0.4064)
			(stroke
				(width 0.1524)
				(type default)
			)
			(layer "B.SilkS")
		)
		(fp_line
			(start -0.7874 -0.4064)
			(end -0.7874 0.4064)
			(stroke
				(width 0.1524)
				(type default)
			)
			(layer "B.SilkS")
		)
		(fp_line
			(start 0.67945 0.3048)
			(end 0.67945 -0.305054)
			(stroke
				(width 0.1)
				(type default)
			)
			(layer "B.Fab")
		)
		(fp_line
			(start 0.67945 -0.305054)
			(end 0.12065 -0.305054)
			(stroke
				(width 0.1)
				(type default)
			)
			(layer "B.Fab")
		)
		(fp_line
			(start 0.12065 0.3048)
			(end 0.67945 0.3048)
			(stroke
				(width 0.1)
				(type default)
			)
			(layer "B.Fab")
		)
		(fp_line
			(start 0.12065 0.2794)
			(end 0.12065 0.3048)
			(stroke
				(width 0.1)
				(type default)
			)
			(layer "B.Fab")
		)
		(fp_line
			(start 0.12065 -0.2794)
			(end -0.12065 -0.2794)
			(stroke
				(width 0.1)
				(type default)
			)
			(layer "B.Fab")
		)
		(fp_line
			(start 0.12065 -0.305054)
			(end 0.12065 -0.2794)
			(stroke
				(width 0.1)
				(type default)
			)
			(layer "B.Fab")
		)
		(fp_line
			(start -0.120396 0.3048)
			(end -0.120396 0.2794)
			(stroke
				(width 0.1)
				(type default)
			)
			(layer "B.Fab")
		)
		(fp_line
			(start -0.120396 0.2794)
			(end 0.12065 0.2794)
			(stroke
				(width 0.1)
				(type default)
			)
			(layer "B.Fab")
		)
		(fp_line
			(start -0.12065 -0.2794)
			(end -0.12065 -0.3048)
			(stroke
				(width 0.1)
				(type default)
			)
			(layer "B.Fab")
		)
		(fp_line
			(start -0.12065 -0.3048)
			(end -0.67945 -0.3048)
			(stroke
				(width 0.1)
				(type default)
			)
			(layer "B.Fab")
		)
		(fp_line
			(start -0.67945 0.3048)
			(end -0.120396 0.3048)
			(stroke
				(width 0.1)
				(type default)
			)
			(layer "B.Fab")
		)
		(fp_line
			(start -0.67945 -0.3048)
			(end -0.67945 0.3048)
			(stroke
				(width 0.1)
				(type default)
			)
			(layer "B.Fab")
		)
		(pad "1" smd circle
			(at 0.40005 0)
			(size 0 0)
			(layers "B.Cu" "B.Mask" "B.Paste")
			(net "PVDDCR_CPU0_P0")
		)
		(pad "2" smd circle
			(at -0.40005 0)
			(size 0 0)
			(layers "B.Cu" "B.Mask" "B.Paste")
			(net "GND")
		)
	)
)
